#ISCELL
  mstr_misc dns *
  *
#ISCELL
  mstr_symbols design_note *
  *
#ISCELL
  mstr_symbols intel_corp_bpage *
  *
#ISCELL
  mstr_standard offpage *
  page182_i1
#CELL
  mstr_discrete res *
  page182_i10
#ISCELL
  mstr_standard offpage *
  page182_i11
#ISCELL
  mstr_standard offpage *
  page182_i12
#ISCELL
  mstr_standard offpage *
  page182_i13
#ISCELL
  mstr_standard offpage *
  page182_i14
#ISCELL
  mstr_standard offpage *
  page182_i15
#ISCELL
  mstr_standard offpage *
  page182_i16
#ISCELL
  mstr_standard offpage *
  page182_i17
#ISCELL
  mstr_standard offpage *
  page182_i18
#ISCELL
  mstr_symbols gnd *
  page182_i19
#ISCELL
  mstr_standard offpage *
  page182_i2
#ISCELL
  mstr_standard tap *
  page182_i20
#ISCELL
  mstr_standard tap *
  page182_i21
#ISCELL
  mstr_standard tap *
  page182_i22
#ISCELL
  mstr_standard tap *
  page182_i23
#ISCELL
  mstr_standard tap *
  page182_i24
#ISCELL
  mstr_standard tap *
  page182_i25
#ISCELL
  mstr_standard tap *
  page182_i26
#ISCELL
  mstr_standard tap *
  page182_i27
#ISCELL
  mstr_standard tap *
  page182_i28
#ISCELL
  mstr_standard tap *
  page182_i29
#ISCELL
  mstr_standard offpage *
  page182_i3
#ISCELL
  mstr_standard tap *
  page182_i30
#ISCELL
  mstr_standard tap *
  page182_i31
#ISCELL
  mstr_standard tap *
  page182_i32
#ISCELL
  mstr_standard tap *
  page182_i33
#ISCELL
  mstr_standard tap *
  page182_i34
#ISCELL
  mstr_symbols gnd *
  page182_i35
#CELL
  mstr_discrete cap *
  page182_i36
#CELL
  mstr_discrete cap *
  page182_i37
#CELL
  mstr_discrete cap *
  page182_i38
#CELL
  mstr_discrete cap *
  page182_i39
#ISCELL
  mstr_standard offpage *
  page182_i4
#CELL
  mstr_discrete cap *
  page182_i40
#CELL
  mstr_discrete cap *
  page182_i41
#CELL
  mstr_discrete cap *
  page182_i42
#CELL
  mstr_discrete cap *
  page182_i43
#CELL
  mstr_discrete cap *
  page182_i44
#CELL
  mstr_discrete cap *
  page182_i45
#CELL
  mstr_discrete cap *
  page182_i46
#CELL
  mstr_discrete cap *
  page182_i47
#CELL
  mstr_discrete cap *
  page182_i48
#CELL
  mstr_discrete cap *
  page182_i49
#ISCELL
  mstr_standard offpage *
  page182_i5
#ISCELL
  mstr_standard offpage *
  page182_i50
#ISCELL
  mstr_standard offpage *
  page182_i51
#CELL
  mstr_discrete cap *
  page182_i52
#CELL
  mstr_discrete cap *
  page182_i53
#ISCELL
  mstr_standard offpage *
  page182_i54
#ISCELL
  mstr_standard offpage *
  page182_i55
#ISCELL
  mstr_standard offpage *
  page182_i56
#ISCELL
  mstr_standard offpage *
  page182_i57
#ISCELL
  mstr_standard offpage *
  page182_i58
#ISCELL
  mstr_standard tap *
  page182_i59
#CELL
  mstr_discrete res *
  page182_i6
#ISCELL
  mstr_standard tap *
  page182_i60
#ISCELL
  mstr_standard tap *
  page182_i61
#ISCELL
  mstr_standard tap *
  page182_i62
#ISCELL
  mstr_standard tap *
  page182_i63
#ISCELL
  mstr_standard tap *
  page182_i64
#ISCELL
  mstr_standard tap *
  page182_i65
#ISCELL
  mstr_standard tap *
  page182_i66
#ISCELL
  mstr_standard tap *
  page182_i67
#ISCELL
  mstr_standard tap *
  page182_i68
#ISCELL
  mstr_standard tap *
  page182_i69
#CELL
  mstr_discrete res *
  page182_i7
#ISCELL
  mstr_standard tap *
  page182_i70
#ISCELL
  mstr_standard tap *
  page182_i71
#ISCELL
  mstr_standard tap *
  page182_i72
#ISCELL
  mstr_standard tap *
  page182_i73
#ISCELL
  mstr_standard tap *
  page182_i74
#ISCELL
  mstr_standard offpage *
  page182_i75
#ISCELL
  mstr_standard offpage *
  page182_i76
#ISCELL
  mstr_standard tap *
  page182_i77
#CELL
  w_hdl dm-fci-conn76-8r-gp-u-01 *
  page182_i79
#CELL
  mstr_discrete res *
  page182_i8
#CELL
  mstr_discrete res *
  page182_i9
